(kicad_pcb
	(version 20260206)
	(generator "pcbnew")
	(generator_version "10.0")
	(general
		(thickness 1.6)
		(legacy_teardrops no)
	)
	(paper "A4")
	(title_block
		(title "fcb — 12433-1M.1206WZS1330.brd")
		(comment 1 "Open Vault / Knox (Wiwynn) / footprints 157-164 of 495")
	)
	(layers
		(0 "F.Cu" signal "TOP")
		(4 "In1.Cu" signal "L2GND")
		(6 "In2.Cu" signal "L3VCC")
		(2 "B.Cu" signal "BOTTOM")
		(9 "F.Adhes" user "F.Adhesive")
		(11 "B.Adhes" user "B.Adhesive")
		(13 "F.Paste" user "Package Geometry/Pastemask Top")
		(15 "B.Paste" user "Package Geometry/Pastemask Bottom")
		(5 "F.SilkS" user "Ref Des/Silkscreen Top")
		(7 "B.SilkS" user "Ref Des/Silkscreen Bottom")
		(1 "F.Mask" user "Board Geometry/Soldermask Top")
		(3 "B.Mask" user "Board Geometry/Soldermask Bottom")
		(17 "Dwgs.User" user "User.Drawings")
		(19 "Cmts.User" user "User.Comments")
		(21 "Eco1.User" user "User.Eco1")
		(23 "Eco2.User" user "User.Eco2")
		(25 "Edge.Cuts" user "Board Geometry/Outline")
		(27 "Margin" user)
		(31 "F.CrtYd" user "Package Geometry/Place Bound Top")
		(29 "B.CrtYd" user "Package Geometry/Place Bound Bottom")
		(35 "F.Fab" user "Ref Des/Assembly Top")
		(33 "B.Fab" user "Ref Des/Assembly Bottom")
	)
	(footprint ""
		(layer "F.Cu")
		(at 21.8948 -197.2818 90)
		(property "Reference" "R180"
			(at 0 0 90)
			(layer "F.SilkS")
			(hide yes)
			(effects
				(font
					(size 1.27 1.27)
				)
			)
		)
		(property "Value" "0R1206-PAD-1-GP"
			(at 0 -5.0292 90)
			(unlocked yes)
			(layer "F.Fab")
			(hide yes)
			(effects
				(font
					(size 1.016 1.016)
					(thickness 0.1524)
				)
			)
		)
		(property "Device Type" "0R1206-PAD-1"
			(at 0 -6.5532 90)
			(unlocked yes)
			(layer "F.Fab")
			(hide yes)
			(effects
				(font
					(size 1.016 1.016)
					(thickness 0.1524)
				)
			)
		)
		(duplicate_pad_numbers_are_jumpers no)
		(fp_line
			(start 1.016 -2.2352)
			(end -1.016 -2.2352)
			(stroke
				(width 0.1524)
				(type default)
			)
			(layer "F.SilkS")
		)
		(fp_line
			(start -1.016 -2.2352)
			(end -1.016 2.2352)
			(stroke
				(width 0.1524)
				(type default)
			)
			(layer "F.SilkS")
		)
		(fp_line
			(start 1.016 2.2352)
			(end 1.016 -2.2352)
			(stroke
				(width 0.1524)
				(type default)
			)
			(layer "F.SilkS")
		)
		(fp_line
			(start -1.016 2.2352)
			(end 1.016 2.2352)
			(stroke
				(width 0.1524)
				(type default)
			)
			(layer "F.SilkS")
		)
		(fp_rect
			(start -1.0922 2.3114)
			(end 1.0922 -2.3114)
			(stroke
				(width 0)
				(type default)
			)
			(fill no)
			(layer "F.CrtYd")
		)
		(fp_poly
			(pts
				(xy -1.0922 -2.3114) (xy 1.0922 -2.3114) (xy 1.0922 2.3114) (xy -1.0922 2.3114)
			)
			(stroke
				(width 0)
				(type default)
			)
			(fill no)
			(layer "F.Fab")
		)
		(pad "1" smd rect
			(at 0 -1.397 90)
			(size 1.651 2.0574)
			(drill
				(offset 0 0.3937)
			)
			(layers "F.Cu" "F.Mask" "F.Paste")
			(net "P12V_FAN4")
		)
		(pad "2" smd rect
			(at 0 1.397 90)
			(size 1.651 2.0574)
			(drill
				(offset 0 -0.3937)
			)
			(layers "F.Cu" "F.Mask" "F.Paste")
			(net "P12V")
		)
	)
	(footprint ""
		(layer "F.Cu")
		(at 33.401 -240.3094 180)
		(property "Reference" "R54"
			(at 0 0 180)
			(layer "F.SilkS")
			(hide yes)
			(effects
				(font
					(size 1.27 1.27)
				)
			)
		)
		(property "Value" "4K7R2J-2-GP"
			(at 0.064008 -3.993896 180)
			(unlocked yes)
			(layer "F.Fab")
			(hide yes)
			(effects
				(font
					(size 1.016 1.016)
					(thickness 0.1524)
				)
			)
		)
		(property "Device Type" "R402H16"
			(at 0.064008 -5.517896 180)
			(unlocked yes)
			(layer "F.Fab")
			(hide yes)
			(effects
				(font
					(size 1.016 1.016)
					(thickness 0.1524)
				)
			)
		)
		(duplicate_pad_numbers_are_jumpers no)
		(fp_line
			(start 0.508 -0.9398)
			(end -0.508 -0.9398)
			(stroke
				(width 0.1524)
				(type default)
			)
			(layer "F.SilkS")
		)
		(fp_line
			(start -0.508 -0.9398)
			(end -0.508 0.9398)
			(stroke
				(width 0.1524)
				(type default)
			)
			(layer "F.SilkS")
		)
		(fp_rect
			(start -0.508 0.9398)
			(end 0.508 -0.9398)
			(stroke
				(width 0)
				(type default)
			)
			(fill no)
			(layer "F.CrtYd")
		)
		(fp_rect
			(start -0.508 0.9398)
			(end 0.508 -0.9398)
			(stroke
				(width 0)
				(type default)
			)
			(fill no)
			(layer "F.Fab")
		)
		(pad "1" smd custom
			(at 0 -0.4445 180)
			(size 0.1397 0.1397)
			(layers "F.Cu" "F.Mask" "F.Paste")
			(net "GND")
			(options
				(clearance outline)
				(anchor circle)
			)
			(primitives
				(gr_poly
					(pts
						(arc
							(start -0.1778 -0.2794)
							(mid -0.249642 -0.249642)
							(end -0.2794 -0.1778)
						)
						(arc
							(start -0.2794 0.1778)
							(mid -0.249642 0.249642)
							(end -0.1778 0.2794)
						)
						(arc
							(start 0.1778 0.2794)
							(mid 0.249642 0.249642)
							(end 0.2794 0.1778)
						)
						(arc
							(start 0.2794 -0.1778)
							(mid 0.249642 -0.249642)
							(end 0.1778 -0.2794)
						)
					)
					(width 0)
					(fill yes)
				)
			)
		)
		(pad "2" smd custom
			(at 0 0.4445 180)
			(size 0.1397 0.1397)
			(layers "F.Cu" "F.Mask" "F.Paste")
			(net "LED_DRV_A0")
			(options
				(clearance outline)
				(anchor circle)
			)
			(primitives
				(gr_poly
					(pts
						(arc
							(start -0.1778 -0.2794)
							(mid -0.249642 -0.249642)
							(end -0.2794 -0.1778)
						)
						(arc
							(start -0.2794 0.1778)
							(mid -0.249642 0.249642)
							(end -0.1778 0.2794)
						)
						(arc
							(start 0.1778 0.2794)
							(mid 0.249642 0.249642)
							(end 0.2794 0.1778)
						)
						(arc
							(start 0.2794 -0.1778)
							(mid 0.249642 -0.249642)
							(end 0.1778 -0.2794)
						)
					)
					(width 0)
					(fill yes)
				)
			)
		)
	)
	(footprint ""
		(layer "F.Cu")
		(at 28.2956 -141.8082 90)
		(property "Reference" "PC97"
			(at 0 0 90)
			(layer "F.SilkS")
			(hide yes)
			(effects
				(font
					(size 1.27 1.27)
				)
			)
		)
		(property "Value" "SC10U25V5KX-GP"
			(at -0.0762 -6.1214 90)
			(unlocked yes)
			(layer "F.Fab")
			(hide yes)
			(effects
				(font
					(size 1.016 1.016)
					(thickness 0.1524)
				)
			)
		)
		(property "Device Type" "C805H56"
			(at -0.0762 -8.1534 90)
			(unlocked yes)
			(layer "F.Fab")
			(hide yes)
			(effects
				(font
					(size 1.016 1.016)
					(thickness 0.1524)
				)
			)
		)
		(duplicate_pad_numbers_are_jumpers no)
		(fp_line
			(start 0.635 0)
			(end -0.635 0)
			(stroke
				(width 0.508)
				(type default)
			)
			(layer "F.SilkS")
		)
		(fp_rect
			(start -0.9652 1.778)
			(end 0.9652 -1.778)
			(stroke
				(width 0)
				(type default)
			)
			(fill no)
			(layer "F.CrtYd")
		)
		(fp_poly
			(pts
				(xy -0.9652 -1.778) (xy 0.9652 -1.778) (xy 0.9652 1.778) (xy -0.9652 1.778)
			)
			(stroke
				(width 0)
				(type default)
			)
			(fill no)
			(layer "F.Fab")
		)
		(pad "1" smd rect
			(at 0 -0.9652 90)
			(size 1.397 1.143)
			(layers "F.Cu" "F.Mask" "F.Paste")
			(net "P12VU_2490_EN_2")
		)
		(pad "2" smd rect
			(at 0 0.9652 90)
			(size 1.397 1.143)
			(layers "F.Cu" "F.Mask" "F.Paste")
			(net "GND")
		)
	)
	(footprint ""
		(layer "F.Cu")
		(at 32.399224 -174.76851 90)
		(property "Reference" "R18"
			(at 0 0 90)
			(layer "F.SilkS")
			(hide yes)
			(effects
				(font
					(size 1.27 1.27)
				)
			)
		)
		(property "Value" "100KR2F-L1-GP"
			(at 0.064008 -3.993896 90)
			(unlocked yes)
			(layer "F.Fab")
			(hide yes)
			(effects
				(font
					(size 1.016 1.016)
					(thickness 0.1524)
				)
			)
		)
		(property "Device Type" "R402H16"
			(at 0.064008 -5.517896 90)
			(unlocked yes)
			(layer "F.Fab")
			(hide yes)
			(effects
				(font
					(size 1.016 1.016)
					(thickness 0.1524)
				)
			)
		)
		(duplicate_pad_numbers_are_jumpers no)
		(fp_line
			(start 0.508 -0.9398)
			(end -0.508 -0.9398)
			(stroke
				(width 0.1524)
				(type default)
			)
			(layer "F.SilkS")
		)
		(fp_line
			(start -0.508 -0.9398)
			(end -0.508 0.9398)
			(stroke
				(width 0.1524)
				(type default)
			)
			(layer "F.SilkS")
		)
		(fp_rect
			(start -0.508 0.9398)
			(end 0.508 -0.9398)
			(stroke
				(width 0)
				(type default)
			)
			(fill no)
			(layer "F.CrtYd")
		)
		(fp_rect
			(start -0.508 0.9398)
			(end 0.508 -0.9398)
			(stroke
				(width 0)
				(type default)
			)
			(fill no)
			(layer "F.Fab")
		)
		(pad "1" smd custom
			(at 0 -0.4445 90)
			(size 0.1397 0.1397)
			(layers "F.Cu" "F.Mask" "F.Paste")
			(net "PWM_EXP_1B")
			(options
				(clearance outline)
				(anchor circle)
			)
			(primitives
				(gr_poly
					(pts
						(arc
							(start -0.1778 -0.2794)
							(mid -0.249642 -0.249642)
							(end -0.2794 -0.1778)
						)
						(arc
							(start -0.2794 0.1778)
							(mid -0.249642 0.249642)
							(end -0.1778 0.2794)
						)
						(arc
							(start 0.1778 0.2794)
							(mid 0.249642 0.249642)
							(end 0.2794 0.1778)
						)
						(arc
							(start 0.2794 -0.1778)
							(mid 0.249642 -0.249642)
							(end 0.1778 -0.2794)
						)
					)
					(width 0)
					(fill yes)
				)
			)
		)
		(pad "2" smd custom
			(at 0 0.4445 90)
			(size 0.1397 0.1397)
			(layers "F.Cu" "F.Mask" "F.Paste")
			(net "GND")
			(options
				(clearance outline)
				(anchor circle)
			)
			(primitives
				(gr_poly
					(pts
						(arc
							(start -0.1778 -0.2794)
							(mid -0.249642 -0.249642)
							(end -0.2794 -0.1778)
						)
						(arc
							(start -0.2794 0.1778)
							(mid -0.249642 0.249642)
							(end -0.1778 0.2794)
						)
						(arc
							(start 0.1778 0.2794)
							(mid 0.249642 0.249642)
							(end 0.2794 0.1778)
						)
						(arc
							(start 0.2794 -0.1778)
							(mid 0.249642 -0.249642)
							(end 0.1778 -0.2794)
						)
					)
					(width 0)
					(fill yes)
				)
			)
		)
	)
	(footprint ""
		(layer "F.Cu")
		(at 39.0652 -361.5436 90)
		(property "Reference" "PR46"
			(at 0 0 90)
			(layer "F.SilkS")
			(hide yes)
			(effects
				(font
					(size 1.27 1.27)
				)
			)
		)
		(property "Value" "51KR2F-L-GP"
			(at 0.064008 -3.993896 90)
			(unlocked yes)
			(layer "F.Fab")
			(hide yes)
			(effects
				(font
					(size 1.016 1.016)
					(thickness 0.1524)
				)
			)
		)
		(property "Device Type" "R402H16"
			(at 0.064008 -5.517896 90)
			(unlocked yes)
			(layer "F.Fab")
			(hide yes)
			(effects
				(font
					(size 1.016 1.016)
					(thickness 0.1524)
				)
			)
		)
		(duplicate_pad_numbers_are_jumpers no)
		(fp_line
			(start 0.508 -0.9398)
			(end -0.508 -0.9398)
			(stroke
				(width 0.1524)
				(type default)
			)
			(layer "F.SilkS")
		)
		(fp_line
			(start -0.508 -0.9398)
			(end -0.508 0.9398)
			(stroke
				(width 0.1524)
				(type default)
			)
			(layer "F.SilkS")
		)
		(fp_rect
			(start -0.508 0.9398)
			(end 0.508 -0.9398)
			(stroke
				(width 0)
				(type default)
			)
			(fill no)
			(layer "F.CrtYd")
		)
		(fp_rect
			(start -0.508 0.9398)
			(end 0.508 -0.9398)
			(stroke
				(width 0)
				(type default)
			)
			(fill no)
			(layer "F.Fab")
		)
		(pad "1" smd custom
			(at 0 -0.4445 90)
			(size 0.1397 0.1397)
			(layers "F.Cu" "F.Mask" "F.Paste")
			(net "P12V_AUX")
			(options
				(clearance outline)
				(anchor circle)
			)
			(primitives
				(gr_poly
					(pts
						(arc
							(start -0.1778 -0.2794)
							(mid -0.249642 -0.249642)
							(end -0.2794 -0.1778)
						)
						(arc
							(start -0.2794 0.1778)
							(mid -0.249642 0.249642)
							(end -0.1778 0.2794)
						)
						(arc
							(start 0.1778 0.2794)
							(mid 0.249642 0.249642)
							(end 0.2794 0.1778)
						)
						(arc
							(start 0.2794 -0.1778)
							(mid 0.249642 -0.249642)
							(end 0.1778 -0.2794)
						)
					)
					(width 0)
					(fill yes)
				)
			)
		)
		(pad "2" smd custom
			(at 0 0.4445 90)
			(size 0.1397 0.1397)
			(layers "F.Cu" "F.Mask" "F.Paste")
			(net "TEMP_ALM#_JP_1")
			(options
				(clearance outline)
				(anchor circle)
			)
			(primitives
				(gr_poly
					(pts
						(arc
							(start -0.1778 -0.2794)
							(mid -0.249642 -0.249642)
							(end -0.2794 -0.1778)
						)
						(arc
							(start -0.2794 0.1778)
							(mid -0.249642 0.249642)
							(end -0.1778 0.2794)
						)
						(arc
							(start 0.1778 0.2794)
							(mid 0.249642 0.249642)
							(end 0.2794 0.1778)
						)
						(arc
							(start 0.2794 -0.1778)
							(mid 0.249642 -0.249642)
							(end 0.1778 -0.2794)
						)
					)
					(width 0)
					(fill yes)
				)
			)
		)
	)
	(footprint ""
		(layer "F.Cu")
		(at 11.9634 -232.7656 90)
		(property "Reference" "R34"
			(at 0 0 90)
			(layer "F.SilkS")
			(hide yes)
			(effects
				(font
					(size 1.27 1.27)
				)
			)
		)
		(property "Value" "0R2J-2-GP"
			(at 0.064008 -3.993896 90)
			(unlocked yes)
			(layer "F.Fab")
			(hide yes)
			(effects
				(font
					(size 1.016 1.016)
					(thickness 0.1524)
				)
			)
		)
		(property "Device Type" "R402H16"
			(at 0.064008 -5.517896 90)
			(unlocked yes)
			(layer "F.Fab")
			(hide yes)
			(effects
				(font
					(size 1.016 1.016)
					(thickness 0.1524)
				)
			)
		)
		(duplicate_pad_numbers_are_jumpers no)
		(fp_line
			(start 0.508 -0.9398)
			(end -0.508 -0.9398)
			(stroke
				(width 0.1524)
				(type default)
			)
			(layer "F.SilkS")
		)
		(fp_line
			(start -0.508 -0.9398)
			(end -0.508 0.9398)
			(stroke
				(width 0.1524)
				(type default)
			)
			(layer "F.SilkS")
		)
		(fp_rect
			(start -0.508 0.9398)
			(end 0.508 -0.9398)
			(stroke
				(width 0)
				(type default)
			)
			(fill no)
			(layer "F.CrtYd")
		)
		(fp_rect
			(start -0.508 0.9398)
			(end 0.508 -0.9398)
			(stroke
				(width 0)
				(type default)
			)
			(fill no)
			(layer "F.Fab")
		)
		(pad "1" smd custom
			(at 0 -0.4445 90)
			(size 0.1397 0.1397)
			(layers "F.Cu" "F.Mask" "F.Paste")
			(net "LED_DR_LED3_K")
			(options
				(clearance outline)
				(anchor circle)
			)
			(primitives
				(gr_poly
					(pts
						(arc
							(start -0.1778 -0.2794)
							(mid -0.249642 -0.249642)
							(end -0.2794 -0.1778)
						)
						(arc
							(start -0.2794 0.1778)
							(mid -0.249642 0.249642)
							(end -0.1778 0.2794)
						)
						(arc
							(start 0.1778 0.2794)
							(mid 0.249642 0.249642)
							(end 0.2794 0.1778)
						)
						(arc
							(start 0.2794 -0.1778)
							(mid 0.249642 -0.249642)
							(end 0.1778 -0.2794)
						)
					)
					(width 0)
					(fill yes)
				)
			)
		)
		(pad "2" smd custom
			(at 0 0.4445 90)
			(size 0.1397 0.1397)
			(layers "F.Cu" "F.Mask" "F.Paste")
			(net "GND")
			(options
				(clearance outline)
				(anchor circle)
			)
			(primitives
				(gr_poly
					(pts
						(arc
							(start -0.1778 -0.2794)
							(mid -0.249642 -0.249642)
							(end -0.2794 -0.1778)
						)
						(arc
							(start -0.2794 0.1778)
							(mid -0.249642 0.249642)
							(end -0.1778 0.2794)
						)
						(arc
							(start 0.1778 0.2794)
							(mid 0.249642 0.249642)
							(end 0.2794 0.1778)
						)
						(arc
							(start 0.2794 -0.1778)
							(mid 0.249642 -0.249642)
							(end 0.1778 -0.2794)
						)
					)
					(width 0)
					(fill yes)
				)
			)
		)
	)
	(footprint ""
		(layer "F.Cu")
		(at 23.1902 -145.161 180)
		(property "Reference" "PR112"
			(at 0 0 180)
			(layer "F.SilkS")
			(hide yes)
			(effects
				(font
					(size 1.27 1.27)
				)
			)
		)
		(property "Value" "6K81R2F-1-GP"
			(at 0.064008 -3.993896 180)
			(unlocked yes)
			(layer "F.Fab")
			(hide yes)
			(effects
				(font
					(size 1.016 1.016)
					(thickness 0.1524)
				)
			)
		)
		(property "Device Type" "R402H16"
			(at 0.064008 -5.517896 180)
			(unlocked yes)
			(layer "F.Fab")
			(hide yes)
			(effects
				(font
					(size 1.016 1.016)
					(thickness 0.1524)
				)
			)
		)
		(duplicate_pad_numbers_are_jumpers no)
		(fp_line
			(start 0.508 -0.9398)
			(end -0.508 -0.9398)
			(stroke
				(width 0.1524)
				(type default)
			)
			(layer "F.SilkS")
		)
		(fp_line
			(start -0.508 -0.9398)
			(end -0.508 0.9398)
			(stroke
				(width 0.1524)
				(type default)
			)
			(layer "F.SilkS")
		)
		(fp_rect
			(start -0.508 0.9398)
			(end 0.508 -0.9398)
			(stroke
				(width 0)
				(type default)
			)
			(fill no)
			(layer "F.CrtYd")
		)
		(fp_rect
			(start -0.508 0.9398)
			(end 0.508 -0.9398)
			(stroke
				(width 0)
				(type default)
			)
			(fill no)
			(layer "F.Fab")
		)
		(pad "1" smd custom
			(at 0 -0.4445 180)
			(size 0.1397 0.1397)
			(layers "F.Cu" "F.Mask" "F.Paste")
			(net "P12VU_2490_EN_2")
			(options
				(clearance outline)
				(anchor circle)
			)
			(primitives
				(gr_poly
					(pts
						(arc
							(start -0.1778 -0.2794)
							(mid -0.249642 -0.249642)
							(end -0.2794 -0.1778)
						)
						(arc
							(start -0.2794 0.1778)
							(mid -0.249642 0.249642)
							(end -0.1778 0.2794)
						)
						(arc
							(start 0.1778 0.2794)
							(mid 0.249642 0.249642)
							(end 0.2794 0.1778)
						)
						(arc
							(start 0.2794 -0.1778)
							(mid 0.249642 -0.249642)
							(end 0.1778 -0.2794)
						)
					)
					(width 0)
					(fill yes)
				)
			)
		)
		(pad "2" smd custom
			(at 0 0.4445 180)
			(size 0.1397 0.1397)
			(layers "F.Cu" "F.Mask" "F.Paste")
			(net "GND")
			(options
				(clearance outline)
				(anchor circle)
			)
			(primitives
				(gr_poly
					(pts
						(arc
							(start -0.1778 -0.2794)
							(mid -0.249642 -0.249642)
							(end -0.2794 -0.1778)
						)
						(arc
							(start -0.2794 0.1778)
							(mid -0.249642 0.249642)
							(end -0.1778 0.2794)
						)
						(arc
							(start 0.1778 0.2794)
							(mid 0.249642 0.249642)
							(end 0.2794 0.1778)
						)
						(arc
							(start 0.2794 -0.1778)
							(mid 0.249642 -0.249642)
							(end 0.1778 -0.2794)
						)
					)
					(width 0)
					(fill yes)
				)
			)
		)
	)
	(footprint ""
		(layer "F.Cu")
		(at 40.26789 -154.147266 180)
		(property "Reference" "L1"
			(at 0 0 180)
			(layer "F.SilkS")
			(hide yes)
			(effects
				(font
					(size 1.27 1.27)
				)
			)
		)
		(property "Value" "FCM1608CF-121T03-GP"
			(at -0.0254 -2.8956 180)
			(unlocked yes)
			(layer "F.Fab")
			(hide yes)
			(effects
				(font
					(size 1.016 1.016)
					(thickness 0.1524)
				)
			)
		)
		(property "Device Type" "L1608-UH38"
			(at -0.0254 -4.4196 180)
			(unlocked yes)
			(layer "F.Fab")
			(hide yes)
			(effects
				(font
					(size 1.016 1.016)
					(thickness 0.1524)
				)
			)
		)
		(duplicate_pad_numbers_are_jumpers no)
		(fp_line
			(start 0.254 0)
			(end -0.254 0)
			(stroke
				(width 0.2032)
				(type default)
			)
			(layer "F.SilkS")
		)
		(fp_rect
			(start -0.5842 1.3335)
			(end 0.5842 -1.3335)
			(stroke
				(width 0)
				(type default)
			)
			(fill no)
			(layer "F.CrtYd")
		)
		(fp_rect
			(start -0.5842 1.3335)
			(end 0.5842 -1.3335)
			(stroke
				(width 0)
				(type default)
			)
			(fill no)
			(layer "F.Fab")
		)
		(pad "1" smd custom
			(at 0 -0.762 180)
			(size 0.2159 0.2159)
			(layers "F.Cu" "F.Mask" "F.Paste")
			(net "P3V3")
			(options
				(clearance outline)
				(anchor circle)
			)
			(primitives
				(gr_poly
					(pts
						(arc
							(start -0.3302 -0.4318)
							(mid -0.402042 -0.402042)
							(end -0.4318 -0.3302)
						)
						(arc
							(start -0.4318 0.3302)
							(mid -0.402042 0.402042)
							(end -0.3302 0.4318)
						)
						(arc
							(start 0.3302 0.4318)
							(mid 0.402042 0.402042)
							(end 0.4318 0.3302)
						)
						(arc
							(start 0.4318 -0.3302)
							(mid 0.402042 -0.402042)
							(end 0.3302 -0.4318)
						)
					)
					(width 0)
					(fill yes)
				)
			)
		)
		(pad "2" smd custom
			(at 0 0.762 180)
			(size 0.2159 0.2159)
			(layers "F.Cu" "F.Mask" "F.Paste")
			(net "NCT7904_3VDD")
			(options
				(clearance outline)
				(anchor circle)
			)
			(primitives
				(gr_poly
					(pts
						(arc
							(start -0.3302 -0.4318)
							(mid -0.402042 -0.402042)
							(end -0.4318 -0.3302)
						)
						(arc
							(start -0.4318 0.3302)
							(mid -0.402042 0.402042)
							(end -0.3302 0.4318)
						)
						(arc
							(start 0.3302 0.4318)
							(mid 0.402042 0.402042)
							(end 0.4318 0.3302)
						)
						(arc
							(start 0.4318 -0.3302)
							(mid 0.402042 -0.402042)
							(end 0.3302 -0.4318)
						)
					)
					(width 0)
					(fill yes)
				)
			)
		)
	)
)
